# BASEBOARD_FAB2 (Tioga Pass) — schematic netlist excerpt (pin names and nets, part order shuffled) for the footprints in the layout excerpt that follows; sources: Cadence DE-HDL packaged netlist, KiCad conversion of Wiwynn_Tioga_Pass_MB.brd

C8G5  CAP  0.22UF 16V 10% X7R  pkg 0402  page 105 : A = P3E_CPU0_PE2_SS_TXP<2> ; B = P3E_CPU0_PE2_SS_C_TXP<2>
C4E3  CAP_A  22.0UF 4V 20% X6S  pkg 0603V  page 202 : A = PVCCIN_CPU0 ; B = GND
C1A9  CAP  1.0UF 16V 10% X6S  pkg 0402  page 227 : A = VR_FET_SW_P12V_STBY_PVDDQ_KLM ; B = GND

(kicad_pcb
	(version 20260206)
	(generator "pcbnew")
	(generator_version "10.0")
	(general
		(thickness 1.6)
		(legacy_teardrops no)
	)
	(paper "A4")
	(title_block
		(title "Wiwynn_Tioga_Pass_MB.brd")
		(comment 1 "Tioga Pass / footprints 272-274 of 4770")
	)
	(layers
		(0 "F.Cu" signal "TOP")
		(4 "In1.Cu" signal "L2GND")
		(6 "In2.Cu" signal "L3")
		(8 "In3.Cu" signal "L4GND")
		(10 "In4.Cu" signal "L5")
		(12 "In5.Cu" signal "L6GND")
		(14 "In6.Cu" signal "L7VCC")
		(16 "In7.Cu" signal "L8VCC")
		(18 "In8.Cu" signal "L9GND")
		(20 "In9.Cu" signal "L10")
		(22 "In10.Cu" signal "L11GND")
		(24 "In11.Cu" signal "L12")
		(26 "In12.Cu" signal "L13GND")
		(2 "B.Cu" signal "BOTTOM")
		(9 "F.Adhes" user "F.Adhesive")
		(11 "B.Adhes" user "B.Adhesive")
		(13 "F.Paste" user "Package Geometry/Pastemask Top")
		(15 "B.Paste" user "Package Geometry/Pastemask Bottom")
		(5 "F.SilkS" user "Ref Des/Silkscreen Top")
		(7 "B.SilkS" user "Ref Des/Silkscreen Bottom")
		(1 "F.Mask" user "Board Geometry/Soldermask Top")
		(3 "B.Mask" user "Board Geometry/Soldermask Bottom")
		(17 "Dwgs.User" user "User.Drawings")
		(19 "Cmts.User" user "User.Comments")
		(21 "Eco1.User" user "User.Eco1")
		(23 "Eco2.User" user "User.Eco2")
		(25 "Edge.Cuts" user "Board Geometry/Outline")
		(27 "Margin" user)
		(31 "F.CrtYd" user "Package Geometry/Place Bound Top")
		(29 "B.CrtYd" user "Package Geometry/Place Bound Bottom")
		(35 "F.Fab" user "Ref Des/Assembly Top")
		(33 "B.Fab" user "Ref Des/Assembly Bottom")
	)
	(footprint ""
		(layer "F.Cu")
		(at 405.231092 -10.917936)
		(property "Reference" "C8G5"
			(at 0 0 0)
			(layer "F.SilkS")
			(hide yes)
			(effects
				(font
					(size 1.27 1.27)
				)
			)
		)
		(property "Value" ""
			(at 0 0 0)
			(layer "F.Fab")
			(effects
				(font
					(size 1.27 1.27)
				)
			)
		)
		(duplicate_pad_numbers_are_jumpers no)
		(fp_rect
			(start -0.3048 0.9906)
			(end 0.3048 -0.1016)
			(stroke
				(width 0)
				(type default)
			)
			(fill no)
			(layer "F.CrtYd")
		)
		(fp_line
			(start -0.3048 -0.1016)
			(end -0.3048 0.9906)
			(stroke
				(width 0.1)
				(type default)
			)
			(layer "F.Fab")
		)
		(fp_line
			(start -0.3048 0.9906)
			(end 0.3048 0.9906)
			(stroke
				(width 0.1)
				(type default)
			)
			(layer "F.Fab")
		)
		(fp_line
			(start 0.3048 -0.1016)
			(end -0.3048 -0.1016)
			(stroke
				(width 0.1)
				(type default)
			)
			(layer "F.Fab")
		)
		(fp_line
			(start 0.3048 0.9906)
			(end 0.3048 -0.1016)
			(stroke
				(width 0.1)
				(type default)
			)
			(layer "F.Fab")
		)
		(pad "1" smd rect
			(at 0 0)
			(size 0.508 0.508)
			(layers "F.Cu" "F.Mask" "F.Paste")
			(net "P3E_CPU0_PE2_SS_TXP<2>")
		)
		(pad "2" smd rect
			(at 0 0.889)
			(size 0.508 0.508)
			(layers "F.Cu" "F.Mask" "F.Paste")
			(net "P3E_CPU0_PE2_SS_C_TXP<2>")
		)
		(zone
			(layer "F.Cu")
			(hatch none 0.5)
			(connect_pads
				(clearance 0)
			)
			(min_thickness 0.25)
			(keepout
				(tracks allowed)
				(vias not_allowed)
				(pads allowed)
				(copperpour not_allowed)
				(footprints allowed)
			)
			(placement
				(enabled no)
				(sheetname "")
			)
			(fill
				(thermal_gap 0.5)
				(thermal_bridge_width 0.5)
				(island_removal_mode 0)
			)
			(polygon
				(pts
					(xy 404.977092 -10.282936) (xy 405.485092 -10.282936) (xy 405.485092 -10.663936) (xy 404.977092 -10.663936)
				)
			)
		)
		(zone
			(layer "F.Cu")
			(hatch none 0.5)
			(connect_pads
				(clearance 0)
			)
			(min_thickness 0.25)
			(keepout
				(tracks not_allowed)
				(vias allowed)
				(pads allowed)
				(copperpour not_allowed)
				(footprints allowed)
			)
			(placement
				(enabled no)
				(sheetname "")
			)
			(fill
				(thermal_gap 0.5)
				(thermal_bridge_width 0.5)
				(island_removal_mode 0)
			)
			(polygon
				(pts
					(xy 404.977092 -10.282936) (xy 405.485092 -10.282936) (xy 405.485092 -10.663936) (xy 404.977092 -10.663936)
				)
			)
		)
	)
	(footprint ""
		(layer "F.Cu")
		(at 214.503 -63.11392)
		(property "Reference" "C4E3"
			(at 0 0 0)
			(layer "F.SilkS")
			(hide yes)
			(effects
				(font
					(size 1.27 1.27)
				)
			)
		)
		(property "Value" ""
			(at 0 0 0)
			(layer "F.Fab")
			(effects
				(font
					(size 1.27 1.27)
				)
			)
		)
		(duplicate_pad_numbers_are_jumpers no)
		(fp_poly
			(pts
				(xy -0.4953 -0.2032) (xy 0.4953 -0.2032) (xy 0.4953 1.6002) (xy -0.4953 1.6002)
			)
			(stroke
				(width 0)
				(type default)
			)
			(fill no)
			(layer "F.CrtYd")
		)
		(fp_line
			(start -0.4953 -0.2032)
			(end 0.4953 -0.2032)
			(stroke
				(width 0.1)
				(type default)
			)
			(layer "F.Fab")
		)
		(fp_line
			(start -0.4953 1.6002)
			(end -0.4953 -0.2032)
			(stroke
				(width 0.1)
				(type default)
			)
			(layer "F.Fab")
		)
		(fp_line
			(start 0.4953 -0.2032)
			(end 0.4953 1.6002)
			(stroke
				(width 0.1)
				(type default)
			)
			(layer "F.Fab")
		)
		(fp_line
			(start 0.4953 1.6002)
			(end -0.4953 1.6002)
			(stroke
				(width 0.1)
				(type default)
			)
			(layer "F.Fab")
		)
		(pad "1" smd rect
			(at 0 0)
			(size 0.762 0.889)
			(layers "F.Cu" "F.Mask" "F.Paste")
			(net "PVCCIN_CPU0")
		)
		(pad "2" smd rect
			(at 0 1.397)
			(size 0.762 0.889)
			(layers "F.Cu" "F.Mask" "F.Paste")
			(net "GND")
		)
		(zone
			(layer "F.Cu")
			(hatch none 0.5)
			(connect_pads
				(clearance 0)
			)
			(min_thickness 0.25)
			(keepout
				(tracks not_allowed)
				(vias allowed)
				(pads allowed)
				(copperpour not_allowed)
				(footprints allowed)
			)
			(placement
				(enabled no)
				(sheetname "")
			)
			(fill
				(thermal_gap 0.5)
				(thermal_bridge_width 0.5)
				(island_removal_mode 0)
			)
			(polygon
				(pts
					(xy 214.122 -62.66942) (xy 214.884 -62.66942) (xy 214.884 -62.16142) (xy 214.122 -62.16142)
				)
			)
		)
	)
	(footprint ""
		(layer "F.Cu")
		(at -1.59639 -150.10511 -90)
		(property "Reference" "C1A9"
			(at 0 0 270)
			(layer "F.SilkS")
			(hide yes)
			(effects
				(font
					(size 1.27 1.27)
				)
			)
		)
		(property "Value" ""
			(at 0 0 270)
			(layer "F.Fab")
			(effects
				(font
					(size 1.27 1.27)
				)
			)
		)
		(duplicate_pad_numbers_are_jumpers no)
		(fp_poly
			(pts
				(xy 0.3048 -0.1016) (xy 0.3048 0.9906) (xy -0.3048 0.9906) (xy -0.3048 -0.1016)
			)
			(stroke
				(width 0)
				(type default)
			)
			(fill no)
			(layer "F.CrtYd")
		)
		(fp_line
			(start -0.3048 0.9906)
			(end 0.3048 0.9906)
			(stroke
				(width 0.1)
				(type default)
			)
			(layer "F.Fab")
		)
		(fp_line
			(start 0.3048 0.9906)
			(end 0.3048 -0.1016)
			(stroke
				(width 0.1)
				(type default)
			)
			(layer "F.Fab")
		)
		(fp_line
			(start -0.3048 -0.1016)
			(end -0.3048 0.9906)
			(stroke
				(width 0.1)
				(type default)
			)
			(layer "F.Fab")
		)
		(fp_line
			(start 0.3048 -0.1016)
			(end -0.3048 -0.1016)
			(stroke
				(width 0.1)
				(type default)
			)
			(layer "F.Fab")
		)
		(pad "1" smd rect
			(at 0 0 270)
			(size 0.508 0.508)
			(layers "F.Cu" "F.Mask" "F.Paste")
			(net "VR_FET_SW_P12V_STBY_PVDDQ_KLM")
		)
		(pad "2" smd rect
			(at 0 0.889 270)
			(size 0.508 0.508)
			(layers "F.Cu" "F.Mask" "F.Paste")
			(net "GND")
		)
		(zone
			(layer "F.Cu")
			(hatch none 0.5)
			(connect_pads
				(clearance 0)
			)
			(min_thickness 0.25)
			(keepout
				(tracks not_allowed)
				(vias allowed)
				(pads allowed)
				(copperpour not_allowed)
				(footprints allowed)
			)
			(placement
				(enabled no)
				(sheetname "")
			)
			(fill
				(thermal_gap 0.5)
				(thermal_bridge_width 0.5)
				(island_removal_mode 0)
			)
			(polygon
				(pts
					(xy -2.23139 -150.35911) (xy -2.23139 -149.85111) (xy -1.85039 -149.85111) (xy -1.85039 -150.35911)
				)
			)
		)
		(zone
			(layer "F.Cu")
			(hatch none 0.5)
			(connect_pads
				(clearance 0)
			)
			(min_thickness 0.25)
			(keepout
				(tracks allowed)
				(vias not_allowed)
				(pads allowed)
				(copperpour not_allowed)
				(footprints allowed)
			)
			(placement
				(enabled no)
				(sheetname "")
			)
			(fill
				(thermal_gap 0.5)
				(thermal_bridge_width 0.5)
				(island_removal_mode 0)
			)
			(polygon
				(pts
					(xy -1.85039 -150.35911) (xy -1.85039 -149.85111) (xy -2.23139 -149.85111) (xy -2.23139 -150.35911)
				)
			)
		)
	)
)
